(kicad_pcb
	(version 20260206)
	(generator "pcbnew")
	(generator_version "10.0")
	(general
		(thickness 1.6)
		(legacy_teardrops no)
	)
	(paper "A4")
	(title_block
		(title "01162023_DA0F0TEBIF0_F0T_Expander_BD_F_brd_V02_OCP.brd")
		(comment 1 "Grand Teton / footprints 5330-5334 of 9728")
	)
	(layers
		(0 "F.Cu" signal "TOP")
		(4 "In1.Cu" signal "GND")
		(6 "In2.Cu" signal "VCC")
		(8 "In3.Cu" signal "VCC1")
		(10 "In4.Cu" signal "GND1")
		(12 "In5.Cu" signal "IN1")
		(14 "In6.Cu" signal "GND2")
		(16 "In7.Cu" signal "IN2")
		(18 "In8.Cu" signal "GND3")
		(20 "In9.Cu" signal "IN3")
		(22 "In10.Cu" signal "GND4")
		(24 "In11.Cu" signal "IN4")
		(26 "In12.Cu" signal "GND5")
		(28 "In13.Cu" signal "IN5")
		(30 "In14.Cu" signal "GND6")
		(32 "In15.Cu" signal "IN6")
		(34 "In16.Cu" signal "GND7")
		(2 "B.Cu" signal "BOTTOM")
		(9 "F.Adhes" user "F.Adhesive")
		(11 "B.Adhes" user "B.Adhesive")
		(13 "F.Paste" user "Package Geometry/Pastemask Top")
		(15 "B.Paste" user "Package Geometry/Pastemask Bottom")
		(5 "F.SilkS" user "Ref Des/Silkscreen Top")
		(7 "B.SilkS" user "Ref Des/Silkscreen Bottom")
		(1 "F.Mask" user "Board Geometry/Soldermask Top")
		(3 "B.Mask" user "Board Geometry/Soldermask Bottom")
		(17 "Dwgs.User" user "User.Drawings")
		(19 "Cmts.User" user "User.Comments")
		(21 "Eco1.User" user "User.Eco1")
		(23 "Eco2.User" user "User.Eco2")
		(25 "Edge.Cuts" user "Board Geometry/Outline")
		(27 "Margin" user)
		(31 "F.CrtYd" user "Package Geometry/Place Bound Top")
		(29 "B.CrtYd" user "Package Geometry/Place Bound Bottom")
		(35 "F.Fab" user "Ref Des/Assembly Top")
		(33 "B.Fab" user "Ref Des/Assembly Bottom")
	)
	(footprint ""
		(layer "F.Cu")
		(at 237.924848 -83.951318 180)
		(property "Reference" "R6724"
			(at 0 0 180)
			(layer "F.SilkS")
			(hide yes)
			(effects
				(font
					(size 1.27 1.27)
				)
			)
		)
		(property "Value" ""
			(at 0 0 180)
			(layer "F.Fab")
			(effects
				(font
					(size 1.27 1.27)
				)
			)
		)
		(duplicate_pad_numbers_are_jumpers no)
		(fp_line
			(start 0.7874 0.4064)
			(end -0.7874 0.4064)
			(stroke
				(width 0.1524)
				(type default)
			)
			(layer "F.SilkS")
		)
		(fp_line
			(start 0.7874 -0.4064)
			(end 0.7874 0.4064)
			(stroke
				(width 0.1524)
				(type default)
			)
			(layer "F.SilkS")
		)
		(fp_line
			(start -0.01651 -0.4064)
			(end 0.7874 -0.4064)
			(stroke
				(width 0.1524)
				(type default)
			)
			(layer "F.SilkS")
		)
		(fp_line
			(start -0.7874 0.4064)
			(end -0.7874 -0.4064)
			(stroke
				(width 0.1524)
				(type default)
			)
			(layer "F.SilkS")
		)
		(fp_line
			(start 0.67945 0.3048)
			(end 0.120396 0.3048)
			(stroke
				(width 0.1)
				(type default)
			)
			(layer "F.Fab")
		)
		(fp_line
			(start 0.67945 -0.3048)
			(end 0.67945 0.3048)
			(stroke
				(width 0.1)
				(type default)
			)
			(layer "F.Fab")
		)
		(fp_line
			(start 0.12065 -0.2794)
			(end 0.12065 -0.3048)
			(stroke
				(width 0.1)
				(type default)
			)
			(layer "F.Fab")
		)
		(fp_line
			(start 0.12065 -0.3048)
			(end 0.67945 -0.3048)
			(stroke
				(width 0.1)
				(type default)
			)
			(layer "F.Fab")
		)
		(fp_line
			(start 0.120396 0.3048)
			(end 0.120396 0.2794)
			(stroke
				(width 0.1)
				(type default)
			)
			(layer "F.Fab")
		)
		(fp_line
			(start 0.120396 0.2794)
			(end -0.12065 0.2794)
			(stroke
				(width 0.1)
				(type default)
			)
			(layer "F.Fab")
		)
		(fp_line
			(start -0.12065 0.3048)
			(end -0.67945 0.3048)
			(stroke
				(width 0.1)
				(type default)
			)
			(layer "F.Fab")
		)
		(fp_line
			(start -0.12065 0.2794)
			(end -0.12065 0.3048)
			(stroke
				(width 0.1)
				(type default)
			)
			(layer "F.Fab")
		)
		(fp_line
			(start -0.12065 -0.2794)
			(end 0.12065 -0.2794)
			(stroke
				(width 0.1)
				(type default)
			)
			(layer "F.Fab")
		)
		(fp_line
			(start -0.12065 -0.305054)
			(end -0.12065 -0.2794)
			(stroke
				(width 0.1)
				(type default)
			)
			(layer "F.Fab")
		)
		(fp_line
			(start -0.67945 0.3048)
			(end -0.67945 -0.305054)
			(stroke
				(width 0.1)
				(type default)
			)
			(layer "F.Fab")
		)
		(fp_line
			(start -0.67945 -0.305054)
			(end -0.12065 -0.305054)
			(stroke
				(width 0.1)
				(type default)
			)
			(layer "F.Fab")
		)
		(pad "1" smd rect
			(at -0.40005 0)
			(size 0.4572 0.508)
			(layers "F.Cu" "F.Mask" "F.Paste")
			(net "USB2_CP2108_CLI_DN")
		)
		(pad "2" smd rect
			(at 0.40005 0)
			(size 0.4572 0.508)
			(layers "F.Cu" "F.Mask" "F.Paste")
			(net "GND")
		)
	)
	(footprint ""
		(layer "F.Cu")
		(at 209.165698 -304.036476 90)
		(property "Reference" "R4178"
			(at 0 0 90)
			(layer "F.SilkS")
			(hide yes)
			(effects
				(font
					(size 1.27 1.27)
				)
			)
		)
		(property "Value" ""
			(at 0 0 90)
			(layer "F.Fab")
			(effects
				(font
					(size 1.27 1.27)
				)
			)
		)
		(duplicate_pad_numbers_are_jumpers no)
		(fp_line
			(start 0.7874 -0.4064)
			(end 0.7874 0.4064)
			(stroke
				(width 0.1524)
				(type default)
			)
			(layer "F.SilkS")
		)
		(fp_line
			(start -0.7874 -0.4064)
			(end 0.7874 -0.4064)
			(stroke
				(width 0.1524)
				(type default)
			)
			(layer "F.SilkS")
		)
		(fp_line
			(start 0.7874 0.4064)
			(end -0.7874 0.4064)
			(stroke
				(width 0.1524)
				(type default)
			)
			(layer "F.SilkS")
		)
		(fp_line
			(start -0.7874 0.4064)
			(end -0.7874 -0.4064)
			(stroke
				(width 0.1524)
				(type default)
			)
			(layer "F.SilkS")
		)
		(fp_line
			(start -0.12065 -0.305054)
			(end -0.12065 -0.2794)
			(stroke
				(width 0.1)
				(type default)
			)
			(layer "F.Fab")
		)
		(fp_line
			(start -0.67945 -0.305054)
			(end -0.12065 -0.305054)
			(stroke
				(width 0.1)
				(type default)
			)
			(layer "F.Fab")
		)
		(fp_line
			(start 0.67945 -0.3048)
			(end 0.67945 0.3048)
			(stroke
				(width 0.1)
				(type default)
			)
			(layer "F.Fab")
		)
		(fp_line
			(start 0.12065 -0.3048)
			(end 0.67945 -0.3048)
			(stroke
				(width 0.1)
				(type default)
			)
			(layer "F.Fab")
		)
		(fp_line
			(start 0.12065 -0.2794)
			(end 0.12065 -0.3048)
			(stroke
				(width 0.1)
				(type default)
			)
			(layer "F.Fab")
		)
		(fp_line
			(start -0.12065 -0.2794)
			(end 0.12065 -0.2794)
			(stroke
				(width 0.1)
				(type default)
			)
			(layer "F.Fab")
		)
		(fp_line
			(start 0.120396 0.2794)
			(end -0.12065 0.2794)
			(stroke
				(width 0.1)
				(type default)
			)
			(layer "F.Fab")
		)
		(fp_line
			(start -0.12065 0.2794)
			(end -0.12065 0.3048)
			(stroke
				(width 0.1)
				(type default)
			)
			(layer "F.Fab")
		)
		(fp_line
			(start 0.67945 0.3048)
			(end 0.120396 0.3048)
			(stroke
				(width 0.1)
				(type default)
			)
			(layer "F.Fab")
		)
		(fp_line
			(start 0.120396 0.3048)
			(end 0.120396 0.2794)
			(stroke
				(width 0.1)
				(type default)
			)
			(layer "F.Fab")
		)
		(fp_line
			(start -0.12065 0.3048)
			(end -0.67945 0.3048)
			(stroke
				(width 0.1)
				(type default)
			)
			(layer "F.Fab")
		)
		(fp_line
			(start -0.67945 0.3048)
			(end -0.67945 -0.305054)
			(stroke
				(width 0.1)
				(type default)
			)
			(layer "F.Fab")
		)
		(pad "1" smd circle
			(at -0.40005 0 90)
			(size 0 0)
			(layers "F.Cu" "F.Mask" "F.Paste")
			(net "GND")
		)
		(pad "2" smd circle
			(at 0.40005 0 90)
			(size 0 0)
			(layers "F.Cu" "F.Mask" "F.Paste")
			(net "PEX1_EXT_GPIO_LATCH_N")
		)
	)
	(footprint ""
		(layer "F.Cu")
		(at 344.918792 -240.691162 90)
		(property "Reference" "R3582"
			(at 0 0 90)
			(layer "F.SilkS")
			(hide yes)
			(effects
				(font
					(size 1.27 1.27)
				)
			)
		)
		(property "Value" ""
			(at 0 0 90)
			(layer "F.Fab")
			(effects
				(font
					(size 1.27 1.27)
				)
			)
		)
		(duplicate_pad_numbers_are_jumpers no)
		(fp_line
			(start 0.7874 -0.4064)
			(end 0.7874 0.4064)
			(stroke
				(width 0.1524)
				(type default)
			)
			(layer "F.SilkS")
		)
		(fp_line
			(start -0.7874 -0.4064)
			(end 0.7874 -0.4064)
			(stroke
				(width 0.1524)
				(type default)
			)
			(layer "F.SilkS")
		)
		(fp_line
			(start 0.7874 0.4064)
			(end -0.7874 0.4064)
			(stroke
				(width 0.1524)
				(type default)
			)
			(layer "F.SilkS")
		)
		(fp_line
			(start -0.7874 0.4064)
			(end -0.7874 -0.4064)
			(stroke
				(width 0.1524)
				(type default)
			)
			(layer "F.SilkS")
		)
		(fp_line
			(start -0.12065 -0.305054)
			(end -0.12065 -0.2794)
			(stroke
				(width 0.1)
				(type default)
			)
			(layer "F.Fab")
		)
		(fp_line
			(start -0.67945 -0.305054)
			(end -0.12065 -0.305054)
			(stroke
				(width 0.1)
				(type default)
			)
			(layer "F.Fab")
		)
		(fp_line
			(start 0.67945 -0.3048)
			(end 0.67945 0.3048)
			(stroke
				(width 0.1)
				(type default)
			)
			(layer "F.Fab")
		)
		(fp_line
			(start 0.12065 -0.3048)
			(end 0.67945 -0.3048)
			(stroke
				(width 0.1)
				(type default)
			)
			(layer "F.Fab")
		)
		(fp_line
			(start 0.12065 -0.2794)
			(end 0.12065 -0.3048)
			(stroke
				(width 0.1)
				(type default)
			)
			(layer "F.Fab")
		)
		(fp_line
			(start -0.12065 -0.2794)
			(end 0.12065 -0.2794)
			(stroke
				(width 0.1)
				(type default)
			)
			(layer "F.Fab")
		)
		(fp_line
			(start 0.120396 0.2794)
			(end -0.12065 0.2794)
			(stroke
				(width 0.1)
				(type default)
			)
			(layer "F.Fab")
		)
		(fp_line
			(start -0.12065 0.2794)
			(end -0.12065 0.3048)
			(stroke
				(width 0.1)
				(type default)
			)
			(layer "F.Fab")
		)
		(fp_line
			(start 0.67945 0.3048)
			(end 0.120396 0.3048)
			(stroke
				(width 0.1)
				(type default)
			)
			(layer "F.Fab")
		)
		(fp_line
			(start 0.120396 0.3048)
			(end 0.120396 0.2794)
			(stroke
				(width 0.1)
				(type default)
			)
			(layer "F.Fab")
		)
		(fp_line
			(start -0.12065 0.3048)
			(end -0.67945 0.3048)
			(stroke
				(width 0.1)
				(type default)
			)
			(layer "F.Fab")
		)
		(fp_line
			(start -0.67945 0.3048)
			(end -0.67945 -0.305054)
			(stroke
				(width 0.1)
				(type default)
			)
			(layer "F.Fab")
		)
		(pad "1" smd circle
			(at -0.40005 0 90)
			(size 0 0)
			(layers "F.Cu" "F.Mask" "F.Paste")
			(net "SSD0_PWRDIS")
		)
		(pad "2" smd circle
			(at 0.40005 0 90)
			(size 0 0)
			(layers "F.Cu" "F.Mask" "F.Paste")
			(net "SSD0_PWRDIS_R")
		)
	)
	(footprint ""
		(layer "F.Cu")
		(at 430.961546 -155.196794 180)
		(property "Reference" "C635"
			(at 0 0 180)
			(layer "F.SilkS")
			(hide yes)
			(effects
				(font
					(size 1.27 1.27)
				)
			)
		)
		(property "Value" ""
			(at 0 0 180)
			(layer "F.Fab")
			(effects
				(font
					(size 1.27 1.27)
				)
			)
		)
		(duplicate_pad_numbers_are_jumpers no)
		(fp_line
			(start 0.299974 0.150114)
			(end -0.299974 0.150114)
			(stroke
				(width 0.1)
				(type default)
			)
			(layer "F.Fab")
		)
		(fp_line
			(start 0.299974 -0.150114)
			(end 0.299974 0.150114)
			(stroke
				(width 0.1)
				(type default)
			)
			(layer "F.Fab")
		)
		(fp_line
			(start -0.299974 0.150114)
			(end -0.299974 -0.150114)
			(stroke
				(width 0.1)
				(type default)
			)
			(layer "F.Fab")
		)
		(fp_line
			(start -0.299974 -0.150114)
			(end 0.299974 -0.150114)
			(stroke
				(width 0.1)
				(type default)
			)
			(layer "F.Fab")
		)
		(pad "1" smd rect
			(at -0.2667 0 180)
			(size 0.3048 0.381)
			(layers "F.Cu" "F.Mask" "F.Paste")
			(net "P5E_PEX3_STN0_TX_DN<15>")
		)
		(pad "2" smd rect
			(at 0.2667 0 180)
			(size 0.3048 0.381)
			(layers "F.Cu" "F.Mask" "F.Paste")
			(net "P5E_PEX3_STN0_TX_C_DN<15>")
		)
	)
	(footprint ""
		(layer "F.Cu")
		(at 77.06233 -22.955504 -90)
		(property "Reference" "C2715"
			(at 0 0 270)
			(layer "F.SilkS")
			(hide yes)
			(effects
				(font
					(size 1.27 1.27)
				)
			)
		)
		(property "Value" ""
			(at 0 0 270)
			(layer "F.Fab")
			(effects
				(font
					(size 1.27 1.27)
				)
			)
		)
		(duplicate_pad_numbers_are_jumpers no)
		(fp_line
			(start -0.7874 0.4064)
			(end -0.7874 -0.4064)
			(stroke
				(width 0.1524)
				(type default)
			)
			(layer "F.SilkS")
		)
		(fp_line
			(start 0.7874 0.4064)
			(end -0.7874 0.4064)
			(stroke
				(width 0.1524)
				(type default)
			)
			(layer "F.SilkS")
		)
		(fp_line
			(start -0.7874 -0.4064)
			(end 0.7874 -0.4064)
			(stroke
				(width 0.1524)
				(type default)
			)
			(layer "F.SilkS")
		)
		(fp_line
			(start 0.7874 -0.4064)
			(end 0.7874 0.4064)
			(stroke
				(width 0.1524)
				(type default)
			)
			(layer "F.SilkS")
		)
		(fp_line
			(start -0.67945 0.3048)
			(end -0.67945 -0.305054)
			(stroke
				(width 0.1)
				(type default)
			)
			(layer "F.Fab")
		)
		(fp_line
			(start -0.12065 0.3048)
			(end -0.67945 0.3048)
			(stroke
				(width 0.1)
				(type default)
			)
			(layer "F.Fab")
		)
		(fp_line
			(start 0.120396 0.3048)
			(end 0.120396 0.2794)
			(stroke
				(width 0.1)
				(type default)
			)
			(layer "F.Fab")
		)
		(fp_line
			(start 0.67945 0.3048)
			(end 0.120396 0.3048)
			(stroke
				(width 0.1)
				(type default)
			)
			(layer "F.Fab")
		)
		(fp_line
			(start -0.12065 0.2794)
			(end -0.12065 0.3048)
			(stroke
				(width 0.1)
				(type default)
			)
			(layer "F.Fab")
		)
		(fp_line
			(start 0.120396 0.2794)
			(end -0.12065 0.2794)
			(stroke
				(width 0.1)
				(type default)
			)
			(layer "F.Fab")
		)
		(fp_line
			(start -0.12065 -0.2794)
			(end 0.12065 -0.2794)
			(stroke
				(width 0.1)
				(type default)
			)
			(layer "F.Fab")
		)
		(fp_line
			(start 0.12065 -0.2794)
			(end 0.12065 -0.3048)
			(stroke
				(width 0.1)
				(type default)
			)
			(layer "F.Fab")
		)
		(fp_line
			(start 0.12065 -0.3048)
			(end 0.67945 -0.3048)
			(stroke
				(width 0.1)
				(type default)
			)
			(layer "F.Fab")
		)
		(fp_line
			(start 0.67945 -0.3048)
			(end 0.67945 0.3048)
			(stroke
				(width 0.1)
				(type default)
			)
			(layer "F.Fab")
		)
		(fp_line
			(start -0.67945 -0.305054)
			(end -0.12065 -0.305054)
			(stroke
				(width 0.1)
				(type default)
			)
			(layer "F.Fab")
		)
		(fp_line
			(start -0.12065 -0.305054)
			(end -0.12065 -0.2794)
			(stroke
				(width 0.1)
				(type default)
			)
			(layer "F.Fab")
		)
		(pad "1" smd circle
			(at -0.40005 0 270)
			(size 0 0)
			(layers "F.Cu" "F.Mask" "F.Paste")
			(net "GND")
		)
		(pad "2" smd circle
			(at 0.40005 0 270)
			(size 0 0)
			(layers "F.Cu" "F.Mask" "F.Paste")
			(net "P3V3_AUX")
		)
	)
)
